(kicad_pcb
	(version 20260206)
	(generator "pcbnew")
	(generator_version "10.0")
	(general
		(thickness 1.6)
		(legacy_teardrops no)
	)
	(paper "A4")
	(title_block
		(title "12092022_DA0F0TYB4D0_F0T_Panel_BD_Front_D_brd_v02_OCP.brd")
		(comment 1 "Grand Teton / footprints 82-88 of 128")
	)
	(layers
		(0 "F.Cu" signal "TOP")
		(4 "In1.Cu" signal "GND")
		(6 "In2.Cu" signal "GND1")
		(2 "B.Cu" signal "BOTTOM")
		(9 "F.Adhes" user "F.Adhesive")
		(11 "B.Adhes" user "B.Adhesive")
		(13 "F.Paste" user "Package Geometry/Pastemask Top")
		(15 "B.Paste" user "Package Geometry/Pastemask Bottom")
		(5 "F.SilkS" user "Ref Des/Silkscreen Top")
		(7 "B.SilkS" user "Ref Des/Silkscreen Bottom")
		(1 "F.Mask" user "Board Geometry/Soldermask Top")
		(3 "B.Mask" user "Board Geometry/Soldermask Bottom")
		(17 "Dwgs.User" user "User.Drawings")
		(19 "Cmts.User" user "User.Comments")
		(21 "Eco1.User" user "User.Eco1")
		(23 "Eco2.User" user "User.Eco2")
		(25 "Edge.Cuts" user "Board Geometry/Outline")
		(27 "Margin" user)
		(31 "F.CrtYd" user "Package Geometry/Place Bound Top")
		(29 "B.CrtYd" user "Package Geometry/Place Bound Bottom")
		(35 "F.Fab" user "Ref Des/Assembly Top")
		(33 "B.Fab" user "Ref Des/Assembly Bottom")
	)
	(footprint ""
		(layer "F.Cu")
		(at 3.048 -28.067 180)
		(property "Reference" "R12"
			(at 0.762 2.00533 0)
			(unlocked yes)
			(layer "F.SilkS")
			(effects
				(font
					(size 0.7874 0.5842)
					(thickness 0.1524)
				)
			)
		)
		(property "Value" ""
			(at 0 0 180)
			(layer "F.Fab")
			(effects
				(font
					(size 1.27 1.27)
				)
			)
		)
		(duplicate_pad_numbers_are_jumpers no)
		(fp_line
			(start 0.7874 0.4064)
			(end -0.7874 0.4064)
			(stroke
				(width 0.1524)
				(type default)
			)
			(layer "F.SilkS")
		)
		(fp_line
			(start 0.7874 -0.4064)
			(end 0.7874 0.4064)
			(stroke
				(width 0.1524)
				(type default)
			)
			(layer "F.SilkS")
		)
		(fp_line
			(start -0.7874 0.4064)
			(end -0.7874 -0.4064)
			(stroke
				(width 0.1524)
				(type default)
			)
			(layer "F.SilkS")
		)
		(fp_line
			(start -0.7874 -0.4064)
			(end 0.7874 -0.4064)
			(stroke
				(width 0.1524)
				(type default)
			)
			(layer "F.SilkS")
		)
		(fp_line
			(start 0.67945 0.3048)
			(end 0.120396 0.3048)
			(stroke
				(width 0.1)
				(type default)
			)
			(layer "F.Fab")
		)
		(fp_line
			(start 0.67945 -0.3048)
			(end 0.67945 0.3048)
			(stroke
				(width 0.1)
				(type default)
			)
			(layer "F.Fab")
		)
		(fp_line
			(start 0.12065 -0.2794)
			(end 0.12065 -0.3048)
			(stroke
				(width 0.1)
				(type default)
			)
			(layer "F.Fab")
		)
		(fp_line
			(start 0.12065 -0.3048)
			(end 0.67945 -0.3048)
			(stroke
				(width 0.1)
				(type default)
			)
			(layer "F.Fab")
		)
		(fp_line
			(start 0.120396 0.3048)
			(end 0.120396 0.2794)
			(stroke
				(width 0.1)
				(type default)
			)
			(layer "F.Fab")
		)
		(fp_line
			(start 0.120396 0.2794)
			(end -0.12065 0.2794)
			(stroke
				(width 0.1)
				(type default)
			)
			(layer "F.Fab")
		)
		(fp_line
			(start -0.12065 0.3048)
			(end -0.67945 0.3048)
			(stroke
				(width 0.1)
				(type default)
			)
			(layer "F.Fab")
		)
		(fp_line
			(start -0.12065 0.2794)
			(end -0.12065 0.3048)
			(stroke
				(width 0.1)
				(type default)
			)
			(layer "F.Fab")
		)
		(fp_line
			(start -0.12065 -0.2794)
			(end 0.12065 -0.2794)
			(stroke
				(width 0.1)
				(type default)
			)
			(layer "F.Fab")
		)
		(fp_line
			(start -0.12065 -0.305054)
			(end -0.12065 -0.2794)
			(stroke
				(width 0.1)
				(type default)
			)
			(layer "F.Fab")
		)
		(fp_line
			(start -0.67945 0.3048)
			(end -0.67945 -0.305054)
			(stroke
				(width 0.1)
				(type default)
			)
			(layer "F.Fab")
		)
		(fp_line
			(start -0.67945 -0.305054)
			(end -0.12065 -0.305054)
			(stroke
				(width 0.1)
				(type default)
			)
			(layer "F.Fab")
		)
		(pad "1" smd circle
			(at -0.40005 0 180)
			(size 0 0)
			(layers "F.Cu" "F.Mask" "F.Paste")
			(net "PWR_LED_R1")
		)
		(pad "2" smd circle
			(at 0.40005 0 180)
			(size 0 0)
			(layers "F.Cu" "F.Mask" "F.Paste")
			(net "GND")
		)
	)
	(footprint ""
		(layer "F.Cu")
		(at 36.703 -22.352)
		(property "Reference" "R38"
			(at -2.032 0.02667 0)
			(unlocked yes)
			(layer "F.SilkS")
			(effects
				(font
					(size 0.7874 0.5842)
					(thickness 0.1524)
				)
			)
		)
		(property "Value" ""
			(at 0 0 0)
			(layer "F.Fab")
			(effects
				(font
					(size 1.27 1.27)
				)
			)
		)
		(duplicate_pad_numbers_are_jumpers no)
		(fp_line
			(start -0.7874 -0.4064)
			(end 0.7874 -0.4064)
			(stroke
				(width 0.1524)
				(type default)
			)
			(layer "F.SilkS")
		)
		(fp_line
			(start -0.7874 0.4064)
			(end -0.7874 -0.4064)
			(stroke
				(width 0.1524)
				(type default)
			)
			(layer "F.SilkS")
		)
		(fp_line
			(start 0.7874 -0.4064)
			(end 0.7874 0.4064)
			(stroke
				(width 0.1524)
				(type default)
			)
			(layer "F.SilkS")
		)
		(fp_line
			(start 0.7874 0.4064)
			(end -0.7874 0.4064)
			(stroke
				(width 0.1524)
				(type default)
			)
			(layer "F.SilkS")
		)
		(fp_line
			(start -0.67945 -0.305054)
			(end -0.12065 -0.305054)
			(stroke
				(width 0.1)
				(type default)
			)
			(layer "F.Fab")
		)
		(fp_line
			(start -0.67945 0.3048)
			(end -0.67945 -0.305054)
			(stroke
				(width 0.1)
				(type default)
			)
			(layer "F.Fab")
		)
		(fp_line
			(start -0.12065 -0.305054)
			(end -0.12065 -0.2794)
			(stroke
				(width 0.1)
				(type default)
			)
			(layer "F.Fab")
		)
		(fp_line
			(start -0.12065 -0.2794)
			(end 0.12065 -0.2794)
			(stroke
				(width 0.1)
				(type default)
			)
			(layer "F.Fab")
		)
		(fp_line
			(start -0.12065 0.2794)
			(end -0.12065 0.3048)
			(stroke
				(width 0.1)
				(type default)
			)
			(layer "F.Fab")
		)
		(fp_line
			(start -0.12065 0.3048)
			(end -0.67945 0.3048)
			(stroke
				(width 0.1)
				(type default)
			)
			(layer "F.Fab")
		)
		(fp_line
			(start 0.120396 0.2794)
			(end -0.12065 0.2794)
			(stroke
				(width 0.1)
				(type default)
			)
			(layer "F.Fab")
		)
		(fp_line
			(start 0.120396 0.3048)
			(end 0.120396 0.2794)
			(stroke
				(width 0.1)
				(type default)
			)
			(layer "F.Fab")
		)
		(fp_line
			(start 0.12065 -0.3048)
			(end 0.67945 -0.3048)
			(stroke
				(width 0.1)
				(type default)
			)
			(layer "F.Fab")
		)
		(fp_line
			(start 0.12065 -0.2794)
			(end 0.12065 -0.3048)
			(stroke
				(width 0.1)
				(type default)
			)
			(layer "F.Fab")
		)
		(fp_line
			(start 0.67945 -0.3048)
			(end 0.67945 0.3048)
			(stroke
				(width 0.1)
				(type default)
			)
			(layer "F.Fab")
		)
		(fp_line
			(start 0.67945 0.3048)
			(end 0.120396 0.3048)
			(stroke
				(width 0.1)
				(type default)
			)
			(layer "F.Fab")
		)
		(pad "1" smd circle
			(at -0.40005 0)
			(size 0 0)
			(layers "F.Cu" "F.Mask" "F.Paste")
			(net "THERMAL_ADDR_A1")
		)
		(pad "2" smd circle
			(at 0.40005 0)
			(size 0 0)
			(layers "F.Cu" "F.Mask" "F.Paste")
			(net "GND")
		)
	)
	(footprint ""
		(layer "F.Cu")
		(at 17.526 -24.13)
		(property "Reference" "R49"
			(at -0.127 -4.16433 0)
			(unlocked yes)
			(layer "F.SilkS")
			(effects
				(font
					(size 0.7874 0.5842)
					(thickness 0.1524)
				)
			)
		)
		(property "Value" ""
			(at 0 0 0)
			(layer "F.Fab")
			(effects
				(font
					(size 1.27 1.27)
				)
			)
		)
		(duplicate_pad_numbers_are_jumpers no)
		(fp_line
			(start -0.7874 -0.4064)
			(end 0.7874 -0.4064)
			(stroke
				(width 0.1524)
				(type default)
			)
			(layer "F.SilkS")
		)
		(fp_line
			(start -0.7874 0.4064)
			(end -0.7874 -0.4064)
			(stroke
				(width 0.1524)
				(type default)
			)
			(layer "F.SilkS")
		)
		(fp_line
			(start 0.7874 -0.4064)
			(end 0.7874 0.4064)
			(stroke
				(width 0.1524)
				(type default)
			)
			(layer "F.SilkS")
		)
		(fp_line
			(start 0.7874 0.4064)
			(end -0.7874 0.4064)
			(stroke
				(width 0.1524)
				(type default)
			)
			(layer "F.SilkS")
		)
		(fp_line
			(start -0.67945 -0.305054)
			(end -0.12065 -0.305054)
			(stroke
				(width 0.1)
				(type default)
			)
			(layer "F.Fab")
		)
		(fp_line
			(start -0.67945 0.3048)
			(end -0.67945 -0.305054)
			(stroke
				(width 0.1)
				(type default)
			)
			(layer "F.Fab")
		)
		(fp_line
			(start -0.12065 -0.305054)
			(end -0.12065 -0.2794)
			(stroke
				(width 0.1)
				(type default)
			)
			(layer "F.Fab")
		)
		(fp_line
			(start -0.12065 -0.2794)
			(end 0.12065 -0.2794)
			(stroke
				(width 0.1)
				(type default)
			)
			(layer "F.Fab")
		)
		(fp_line
			(start -0.12065 0.2794)
			(end -0.12065 0.3048)
			(stroke
				(width 0.1)
				(type default)
			)
			(layer "F.Fab")
		)
		(fp_line
			(start -0.12065 0.3048)
			(end -0.67945 0.3048)
			(stroke
				(width 0.1)
				(type default)
			)
			(layer "F.Fab")
		)
		(fp_line
			(start 0.120396 0.2794)
			(end -0.12065 0.2794)
			(stroke
				(width 0.1)
				(type default)
			)
			(layer "F.Fab")
		)
		(fp_line
			(start 0.120396 0.3048)
			(end 0.120396 0.2794)
			(stroke
				(width 0.1)
				(type default)
			)
			(layer "F.Fab")
		)
		(fp_line
			(start 0.12065 -0.3048)
			(end 0.67945 -0.3048)
			(stroke
				(width 0.1)
				(type default)
			)
			(layer "F.Fab")
		)
		(fp_line
			(start 0.12065 -0.2794)
			(end 0.12065 -0.3048)
			(stroke
				(width 0.1)
				(type default)
			)
			(layer "F.Fab")
		)
		(fp_line
			(start 0.67945 -0.3048)
			(end 0.67945 0.3048)
			(stroke
				(width 0.1)
				(type default)
			)
			(layer "F.Fab")
		)
		(fp_line
			(start 0.67945 0.3048)
			(end 0.120396 0.3048)
			(stroke
				(width 0.1)
				(type default)
			)
			(layer "F.Fab")
		)
		(pad "1" smd circle
			(at -0.40005 0)
			(size 0 0)
			(layers "F.Cu" "F.Mask" "F.Paste")
			(net "SMB_IO_DEBUG_CARD_SDA")
		)
		(pad "2" smd circle
			(at 0.40005 0)
			(size 0 0)
			(layers "F.Cu" "F.Mask" "F.Paste")
			(net "SMB_SDA")
		)
	)
	(footprint ""
		(layer "F.Cu")
		(at 31.609792 -20.163536 180)
		(property "Reference" "U8"
			(at 2.49555 -0.042418 0)
			(unlocked yes)
			(layer "F.SilkS")
			(effects
				(font
					(size 0.7874 0.5842)
					(thickness 0.1524)
				)
				(justify left)
			)
		)
		(property "Value" ""
			(at 0 0 180)
			(layer "F.Fab")
			(effects
				(font
					(size 1.27 1.27)
				)
			)
		)
		(duplicate_pad_numbers_are_jumpers no)
		(fp_line
			(start 0.517398 1.500124)
			(end -0.517398 1.500124)
			(stroke
				(width 0.1524)
				(type default)
			)
			(layer "F.SilkS")
		)
		(fp_line
			(start 0.517398 -1.500124)
			(end 0.517398 1.500124)
			(stroke
				(width 0.1524)
				(type default)
			)
			(layer "F.SilkS")
		)
		(fp_line
			(start -0.517398 1.500124)
			(end -0.517398 -1.500124)
			(stroke
				(width 0.1524)
				(type default)
			)
			(layer "F.SilkS")
		)
		(fp_line
			(start -0.517398 -1.500124)
			(end 0.517398 -1.500124)
			(stroke
				(width 0.1524)
				(type default)
			)
			(layer "F.SilkS")
		)
		(fp_poly
			(pts
				(xy -0.362966 -1.62814) (xy 0.310642 -1.852422) (xy -0.13843 -2.301494)
			)
			(stroke
				(width 0)
				(type default)
			)
			(fill yes)
			(layer "F.SilkS")
		)
		(fp_line
			(start 0.700024 1.500124)
			(end -0.700024 1.500124)
			(stroke
				(width 0.1)
				(type default)
			)
			(layer "F.Fab")
		)
		(fp_line
			(start 0.700024 -1.500124)
			(end 0.700024 1.500124)
			(stroke
				(width 0.1)
				(type default)
			)
			(layer "F.Fab")
		)
		(fp_line
			(start -0.700024 1.500124)
			(end -0.700024 -1.500124)
			(stroke
				(width 0.1)
				(type default)
			)
			(layer "F.Fab")
		)
		(fp_line
			(start -0.700024 -1.500124)
			(end 0.700024 -1.500124)
			(stroke
				(width 0.1)
				(type default)
			)
			(layer "F.Fab")
		)
		(fp_poly
			(pts
				(xy -1.5113 -0.750062) (xy -2.1463 -1.067562) (xy -2.1463 -0.432562)
			)
			(stroke
				(width 0)
				(type default)
			)
			(fill yes)
			(layer "F.Fab")
		)
		(pad "1" smd rect
			(at -0.999998 -0.750062 180)
			(size 0.7112 1.016)
			(layers "F.Cu" "F.Mask" "F.Paste")
			(net "GND")
		)
		(pad "2" smd rect
			(at -0.999998 0.94996 90)
			(size 0.6096 0.7112)
			(layers "F.Cu" "F.Mask" "F.Paste")
			(net "USB2_DEBUG_DP")
		)
		(pad "3" smd rect
			(at 0.999998 0.94996 90)
			(size 0.6096 0.7112)
			(layers "F.Cu" "F.Mask" "F.Paste")
			(net "USB2_DEBUG_DN")
		)
		(pad "4" smd rect
			(at 0.999998 -0.94996 90)
			(size 0.6096 0.7112)
			(layers "F.Cu" "F.Mask" "F.Paste")
			(net "P5V_STBY_DEBUG")
		)
	)
	(footprint ""
		(layer "F.Cu")
		(at 29.591 -32.004)
		(property "Reference" "C8"
			(at -1.651 0.02667 0)
			(unlocked yes)
			(layer "F.SilkS")
			(effects
				(font
					(size 0.7874 0.5842)
					(thickness 0.1524)
				)
			)
		)
		(property "Value" ""
			(at 0 0 0)
			(layer "F.Fab")
			(effects
				(font
					(size 1.27 1.27)
				)
			)
		)
		(duplicate_pad_numbers_are_jumpers no)
		(fp_line
			(start -0.7874 -0.4064)
			(end 0.7874 -0.4064)
			(stroke
				(width 0.1524)
				(type default)
			)
			(layer "F.SilkS")
		)
		(fp_line
			(start -0.7874 0.4064)
			(end -0.7874 -0.4064)
			(stroke
				(width 0.1524)
				(type default)
			)
			(layer "F.SilkS")
		)
		(fp_line
			(start 0.7874 -0.4064)
			(end 0.7874 0.4064)
			(stroke
				(width 0.1524)
				(type default)
			)
			(layer "F.SilkS")
		)
		(fp_line
			(start 0.7874 0.4064)
			(end -0.7874 0.4064)
			(stroke
				(width 0.1524)
				(type default)
			)
			(layer "F.SilkS")
		)
		(fp_line
			(start -0.67945 -0.305054)
			(end -0.12065 -0.305054)
			(stroke
				(width 0.1)
				(type default)
			)
			(layer "F.Fab")
		)
		(fp_line
			(start -0.67945 0.3048)
			(end -0.67945 -0.305054)
			(stroke
				(width 0.1)
				(type default)
			)
			(layer "F.Fab")
		)
		(fp_line
			(start -0.12065 -0.305054)
			(end -0.12065 -0.2794)
			(stroke
				(width 0.1)
				(type default)
			)
			(layer "F.Fab")
		)
		(fp_line
			(start -0.12065 -0.2794)
			(end 0.12065 -0.2794)
			(stroke
				(width 0.1)
				(type default)
			)
			(layer "F.Fab")
		)
		(fp_line
			(start -0.12065 0.2794)
			(end -0.12065 0.3048)
			(stroke
				(width 0.1)
				(type default)
			)
			(layer "F.Fab")
		)
		(fp_line
			(start -0.12065 0.3048)
			(end -0.67945 0.3048)
			(stroke
				(width 0.1)
				(type default)
			)
			(layer "F.Fab")
		)
		(fp_line
			(start 0.120396 0.2794)
			(end -0.12065 0.2794)
			(stroke
				(width 0.1)
				(type default)
			)
			(layer "F.Fab")
		)
		(fp_line
			(start 0.120396 0.3048)
			(end 0.120396 0.2794)
			(stroke
				(width 0.1)
				(type default)
			)
			(layer "F.Fab")
		)
		(fp_line
			(start 0.12065 -0.3048)
			(end 0.67945 -0.3048)
			(stroke
				(width 0.1)
				(type default)
			)
			(layer "F.Fab")
		)
		(fp_line
			(start 0.12065 -0.2794)
			(end 0.12065 -0.3048)
			(stroke
				(width 0.1)
				(type default)
			)
			(layer "F.Fab")
		)
		(fp_line
			(start 0.67945 -0.3048)
			(end 0.67945 0.3048)
			(stroke
				(width 0.1)
				(type default)
			)
			(layer "F.Fab")
		)
		(fp_line
			(start 0.67945 0.3048)
			(end 0.120396 0.3048)
			(stroke
				(width 0.1)
				(type default)
			)
			(layer "F.Fab")
		)
		(pad "1" smd circle
			(at -0.40005 0)
			(size 0 0)
			(layers "F.Cu" "F.Mask" "F.Paste")
			(net "P5V_STBY")
		)
		(pad "2" smd circle
			(at 0.40005 0)
			(size 0 0)
			(layers "F.Cu" "F.Mask" "F.Paste")
			(net "GND")
		)
	)
	(footprint ""
		(layer "F.Cu")
		(at 35.941 -34.163)
		(property "Reference" "C16"
			(at 0.762 -4.67233 0)
			(unlocked yes)
			(layer "F.SilkS")
			(effects
				(font
					(size 0.7874 0.5842)
					(thickness 0.1524)
				)
				(justify left)
			)
		)
		(property "Value" ""
			(at 0 0 0)
			(layer "F.Fab")
			(effects
				(font
					(size 1.27 1.27)
				)
			)
		)
		(duplicate_pad_numbers_are_jumpers no)
		(fp_line
			(start -1.524 -0.762)
			(end 1.524 -0.762)
			(stroke
				(width 0.1524)
				(type default)
			)
			(layer "F.SilkS")
		)
		(fp_line
			(start -1.524 0.762)
			(end -1.524 -0.762)
			(stroke
				(width 0.1524)
				(type default)
			)
			(layer "F.SilkS")
		)
		(fp_line
			(start 1.524 -0.762)
			(end 1.524 0.762)
			(stroke
				(width 0.1524)
				(type default)
			)
			(layer "F.SilkS")
		)
		(fp_line
			(start 1.524 0.762)
			(end -1.524 0.762)
			(stroke
				(width 0.1524)
				(type default)
			)
			(layer "F.SilkS")
		)
		(fp_line
			(start -1.1049 -0.724916)
			(end -1.1049 0.724916)
			(stroke
				(width 0.1)
				(type default)
			)
			(layer "F.Fab")
		)
		(fp_line
			(start -1.1049 0.724916)
			(end 1.1049 0.724916)
			(stroke
				(width 0.1)
				(type default)
			)
			(layer "F.Fab")
		)
		(fp_line
			(start 1.1049 -0.724916)
			(end -1.1049 -0.724916)
			(stroke
				(width 0.1)
				(type default)
			)
			(layer "F.Fab")
		)
		(fp_line
			(start 1.1049 0.724916)
			(end 1.1049 -0.724916)
			(stroke
				(width 0.1)
				(type default)
			)
			(layer "F.Fab")
		)
		(pad "1" smd rect
			(at -0.889 0 180)
			(size 1.016 1.27)
			(layers "F.Cu" "F.Mask" "F.Paste")
			(net "P5V_STBY_DEBUG")
		)
		(pad "2" smd rect
			(at 0.889 0 180)
			(size 1.016 1.27)
			(layers "F.Cu" "F.Mask" "F.Paste")
			(net "GND")
		)
	)
	(footprint ""
		(layer "F.Cu")
		(at 5.969 -61.341 180)
		(property "Reference" "R19"
			(at 2.667 -0.40767 0)
			(unlocked yes)
			(layer "F.SilkS")
			(effects
				(font
					(size 0.7874 0.5842)
					(thickness 0.1524)
				)
			)
		)
		(property "Value" ""
			(at 0 0 180)
			(layer "F.Fab")
			(effects
				(font
					(size 1.27 1.27)
				)
			)
		)
		(duplicate_pad_numbers_are_jumpers no)
		(fp_line
			(start 0.7874 0.4064)
			(end -0.7874 0.4064)
			(stroke
				(width 0.1524)
				(type default)
			)
			(layer "F.SilkS")
		)
		(fp_line
			(start 0.7874 -0.4064)
			(end 0.7874 0.4064)
			(stroke
				(width 0.1524)
				(type default)
			)
			(layer "F.SilkS")
		)
		(fp_line
			(start -0.7874 0.4064)
			(end -0.7874 -0.4064)
			(stroke
				(width 0.1524)
				(type default)
			)
			(layer "F.SilkS")
		)
		(fp_line
			(start -0.7874 -0.4064)
			(end 0.7874 -0.4064)
			(stroke
				(width 0.1524)
				(type default)
			)
			(layer "F.SilkS")
		)
		(fp_line
			(start 0.67945 0.3048)
			(end 0.120396 0.3048)
			(stroke
				(width 0.1)
				(type default)
			)
			(layer "F.Fab")
		)
		(fp_line
			(start 0.67945 -0.3048)
			(end 0.67945 0.3048)
			(stroke
				(width 0.1)
				(type default)
			)
			(layer "F.Fab")
		)
		(fp_line
			(start 0.12065 -0.2794)
			(end 0.12065 -0.3048)
			(stroke
				(width 0.1)
				(type default)
			)
			(layer "F.Fab")
		)
		(fp_line
			(start 0.12065 -0.3048)
			(end 0.67945 -0.3048)
			(stroke
				(width 0.1)
				(type default)
			)
			(layer "F.Fab")
		)
		(fp_line
			(start 0.120396 0.3048)
			(end 0.120396 0.2794)
			(stroke
				(width 0.1)
				(type default)
			)
			(layer "F.Fab")
		)
		(fp_line
			(start 0.120396 0.2794)
			(end -0.12065 0.2794)
			(stroke
				(width 0.1)
				(type default)
			)
			(layer "F.Fab")
		)
		(fp_line
			(start -0.12065 0.3048)
			(end -0.67945 0.3048)
			(stroke
				(width 0.1)
				(type default)
			)
			(layer "F.Fab")
		)
		(fp_line
			(start -0.12065 0.2794)
			(end -0.12065 0.3048)
			(stroke
				(width 0.1)
				(type default)
			)
			(layer "F.Fab")
		)
		(fp_line
			(start -0.12065 -0.2794)
			(end 0.12065 -0.2794)
			(stroke
				(width 0.1)
				(type default)
			)
			(layer "F.Fab")
		)
		(fp_line
			(start -0.12065 -0.305054)
			(end -0.12065 -0.2794)
			(stroke
				(width 0.1)
				(type default)
			)
			(layer "F.Fab")
		)
		(fp_line
			(start -0.67945 0.3048)
			(end -0.67945 -0.305054)
			(stroke
				(width 0.1)
				(type default)
			)
			(layer "F.Fab")
		)
		(fp_line
			(start -0.67945 -0.305054)
			(end -0.12065 -0.305054)
			(stroke
				(width 0.1)
				(type default)
			)
			(layer "F.Fab")
		)
		(pad "1" smd circle
			(at -0.40005 0 180)
			(size 0 0)
			(layers "F.Cu" "F.Mask" "F.Paste")
			(net "PCA9539_A1")
		)
		(pad "2" smd circle
			(at 0.40005 0 180)
			(size 0 0)
			(layers "F.Cu" "F.Mask" "F.Paste")
			(net "P3V3_STBY")
		)
	)
)
